(kicad_pcb
	(version 20260206)
	(generator "pcbnew")
	(generator_version "10.0")
	(general
		(thickness 1.6)
		(legacy_teardrops no)
	)
	(paper "A4")
	(title_block
		(title "baseboard — 13948-1b.1110WZS1818.brd")
		(comment 1 "Honey Badger (Wiwynn) / footprints 2393-2400 of 2523")
	)
	(layers
		(0 "F.Cu" signal "TOP")
		(4 "In1.Cu" signal "L2GND")
		(6 "In2.Cu" signal "L3")
		(8 "In3.Cu" signal "L4VCC")
		(10 "In4.Cu" signal "L5VCC")
		(12 "In5.Cu" signal "L6")
		(14 "In6.Cu" signal "L7GND")
		(2 "B.Cu" signal "BOTTOM")
		(9 "F.Adhes" user "F.Adhesive")
		(11 "B.Adhes" user "B.Adhesive")
		(13 "F.Paste" user "Package Geometry/Pastemask Top")
		(15 "B.Paste" user "Package Geometry/Pastemask Bottom")
		(5 "F.SilkS" user "Ref Des/Silkscreen Top")
		(7 "B.SilkS" user "Ref Des/Silkscreen Bottom")
		(1 "F.Mask" user "Board Geometry/Soldermask Top")
		(3 "B.Mask" user "Board Geometry/Soldermask Bottom")
		(17 "Dwgs.User" user "User.Drawings")
		(19 "Cmts.User" user "User.Comments")
		(21 "Eco1.User" user "User.Eco1")
		(23 "Eco2.User" user "User.Eco2")
		(25 "Edge.Cuts" user "Board Geometry/Outline")
		(27 "Margin" user)
		(31 "F.CrtYd" user "Package Geometry/Place Bound Top")
		(29 "B.CrtYd" user "Package Geometry/Place Bound Bottom")
		(35 "F.Fab" user "Ref Des/Assembly Top")
		(33 "B.Fab" user "Ref Des/Assembly Bottom")
	)
	(footprint ""
		(layer "B.Cu")
		(at 96.349566 -40.2844 90)
		(property "Reference" "SC966"
			(at 0 0 90)
			(layer "B.SilkS")
			(hide yes)
			(effects
				(font
					(size 1.27 1.27)
				)
				(justify mirror)
			)
		)
		(property "Value" "SCD1U6D3V1KX-GP"
			(at 2.8321 -1.7399 90)
			(unlocked yes)
			(layer "B.Fab")
			(hide yes)
			(effects
				(font
					(size 1.016 1.016)
					(thickness 0.1524)
				)
				(justify mirror)
			)
		)
		(property "Device Type" "C0201H13"
			(at 2.8321 -3.2639 90)
			(unlocked yes)
			(layer "B.Fab")
			(hide yes)
			(effects
				(font
					(size 1.016 1.016)
					(thickness 0.1524)
				)
				(justify mirror)
			)
		)
		(duplicate_pad_numbers_are_jumpers no)
		(fp_rect
			(start 0.2794 0.6477)
			(end -0.2794 -0.6477)
			(stroke
				(width 0)
				(type default)
			)
			(fill no)
			(layer "B.CrtYd")
		)
		(fp_rect
			(start 0.2794 0.6477)
			(end -0.2794 -0.6477)
			(stroke
				(width 0)
				(type default)
			)
			(fill no)
			(layer "B.Fab")
		)
		(pad "1" smd custom
			(at 0 -0.2794 270)
			(size 0.0762 0.0762)
			(layers "B.Cu" "B.Mask" "B.Paste")
			(net "SAS0_AVDD")
			(options
				(clearance outline)
				(anchor circle)
			)
			(primitives
				(gr_poly
					(pts
						(arc
							(start 0.1524 0.127)
							(mid 0.137521 0.162921)
							(end 0.1016 0.1778)
						)
						(arc
							(start -0.1016 0.1778)
							(mid -0.137521 0.162921)
							(end -0.1524 0.127)
						)
						(arc
							(start -0.1524 -0.127)
							(mid -0.137521 -0.162921)
							(end -0.1016 -0.1778)
						)
						(arc
							(start 0.1016 -0.1778)
							(mid 0.137521 -0.162921)
							(end 0.1524 -0.127)
						)
					)
					(width 0)
					(fill yes)
				)
			)
		)
		(pad "2" smd custom
			(at 0 0.2794 270)
			(size 0.0762 0.0762)
			(layers "B.Cu" "B.Mask" "B.Paste")
			(net "GND")
			(options
				(clearance outline)
				(anchor circle)
			)
			(primitives
				(gr_poly
					(pts
						(arc
							(start 0.1524 0.127)
							(mid 0.137521 0.162921)
							(end 0.1016 0.1778)
						)
						(arc
							(start -0.1016 0.1778)
							(mid -0.137521 0.162921)
							(end -0.1524 0.127)
						)
						(arc
							(start -0.1524 -0.127)
							(mid -0.137521 -0.162921)
							(end -0.1016 -0.1778)
						)
						(arc
							(start 0.1016 -0.1778)
							(mid 0.137521 -0.162921)
							(end 0.1524 -0.127)
						)
					)
					(width 0)
					(fill yes)
				)
			)
		)
	)
	(footprint ""
		(layer "B.Cu")
		(at 93.35516 -31.623)
		(property "Reference" "SC861"
			(at 0 0 0)
			(layer "B.SilkS")
			(hide yes)
			(effects
				(font
					(size 1.27 1.27)
				)
				(justify mirror)
			)
		)
		(property "Value" "SCD22U6D3V1MX-1-GP"
			(at 2.8321 -1.7399 0)
			(unlocked yes)
			(layer "B.Fab")
			(hide yes)
			(effects
				(font
					(size 1.016 1.016)
					(thickness 0.1524)
				)
				(justify mirror)
			)
		)
		(property "Device Type" "C0201H13"
			(at 2.8321 -3.2639 0)
			(unlocked yes)
			(layer "B.Fab")
			(hide yes)
			(effects
				(font
					(size 1.016 1.016)
					(thickness 0.1524)
				)
				(justify mirror)
			)
		)
		(duplicate_pad_numbers_are_jumpers no)
		(fp_rect
			(start 0.2794 0.6477)
			(end -0.2794 -0.6477)
			(stroke
				(width 0)
				(type default)
			)
			(fill no)
			(layer "B.CrtYd")
		)
		(fp_rect
			(start 0.2794 0.6477)
			(end -0.2794 -0.6477)
			(stroke
				(width 0)
				(type default)
			)
			(fill no)
			(layer "B.Fab")
		)
		(pad "1" smd custom
			(at 0 -0.2794 180)
			(size 0.0762 0.0762)
			(layers "B.Cu" "B.Mask" "B.Paste")
			(net "PCIE_SAS_C_CPU_RX_P0")
			(options
				(clearance outline)
				(anchor circle)
			)
			(primitives
				(gr_poly
					(pts
						(arc
							(start 0.1524 0.127)
							(mid 0.137521 0.162921)
							(end 0.1016 0.1778)
						)
						(arc
							(start -0.1016 0.1778)
							(mid -0.137521 0.162921)
							(end -0.1524 0.127)
						)
						(arc
							(start -0.1524 -0.127)
							(mid -0.137521 -0.162921)
							(end -0.1016 -0.1778)
						)
						(arc
							(start 0.1016 -0.1778)
							(mid 0.137521 -0.162921)
							(end 0.1524 -0.127)
						)
					)
					(width 0)
					(fill yes)
				)
			)
		)
		(pad "2" smd custom
			(at 0 0.2794 180)
			(size 0.0762 0.0762)
			(layers "B.Cu" "B.Mask" "B.Paste")
			(net "PCIE_SAS_CPU_RX_P0")
			(options
				(clearance outline)
				(anchor circle)
			)
			(primitives
				(gr_poly
					(pts
						(arc
							(start 0.1524 0.127)
							(mid 0.137521 0.162921)
							(end 0.1016 0.1778)
						)
						(arc
							(start -0.1016 0.1778)
							(mid -0.137521 0.162921)
							(end -0.1524 0.127)
						)
						(arc
							(start -0.1524 -0.127)
							(mid -0.137521 -0.162921)
							(end -0.1016 -0.1778)
						)
						(arc
							(start 0.1016 -0.1778)
							(mid 0.137521 -0.162921)
							(end 0.1524 -0.127)
						)
					)
					(width 0)
					(fill yes)
				)
			)
		)
	)
	(footprint ""
		(layer "B.Cu")
		(at 123.298966 -40.259 90)
		(property "Reference" "SC973"
			(at 0 0 90)
			(layer "B.SilkS")
			(hide yes)
			(effects
				(font
					(size 1.27 1.27)
				)
				(justify mirror)
			)
		)
		(property "Value" "SCD1U16V2KX-3GP"
			(at -1.1811 -2.7051 90)
			(unlocked yes)
			(layer "B.Fab")
			(hide yes)
			(effects
				(font
					(size 1.016 1.016)
					(thickness 0.1524)
				)
				(justify mirror)
			)
		)
		(property "Device Type" "C402H22"
			(at -1.1811 -4.2291 90)
			(unlocked yes)
			(layer "B.Fab")
			(hide yes)
			(effects
				(font
					(size 1.016 1.016)
					(thickness 0.1524)
				)
				(justify mirror)
			)
		)
		(duplicate_pad_numbers_are_jumpers no)
		(fp_rect
			(start 0.4318 0.9525)
			(end -0.4318 -0.9525)
			(stroke
				(width 0)
				(type default)
			)
			(fill no)
			(layer "B.CrtYd")
		)
		(fp_rect
			(start 0.4318 0.9525)
			(end -0.4318 -0.9525)
			(stroke
				(width 0)
				(type default)
			)
			(fill no)
			(layer "B.Fab")
		)
		(pad "1" smd custom
			(at 0 -0.4445 270)
			(size 0.1524 0.1524)
			(layers "B.Cu" "B.Mask" "B.Paste")
			(net "P1V8_C")
			(options
				(clearance outline)
				(anchor circle)
			)
			(primitives
				(gr_poly
					(pts
						(arc
							(start 0.3048 0.2032)
							(mid 0.275042 0.275042)
							(end 0.2032 0.3048)
						)
						(arc
							(start -0.2032 0.3048)
							(mid -0.275042 0.275042)
							(end -0.3048 0.2032)
						)
						(arc
							(start -0.3048 -0.2032)
							(mid -0.275042 -0.275042)
							(end -0.2032 -0.3048)
						)
						(arc
							(start 0.2032 -0.3048)
							(mid 0.275042 -0.275042)
							(end 0.3048 -0.2032)
						)
					)
					(width 0)
					(fill yes)
				)
			)
		)
		(pad "2" smd custom
			(at 0 0.4445 270)
			(size 0.1524 0.1524)
			(layers "B.Cu" "B.Mask" "B.Paste")
			(net "GND")
			(options
				(clearance outline)
				(anchor circle)
			)
			(primitives
				(gr_poly
					(pts
						(arc
							(start 0.3048 0.2032)
							(mid 0.275042 0.275042)
							(end 0.2032 0.3048)
						)
						(arc
							(start -0.2032 0.3048)
							(mid -0.275042 0.275042)
							(end -0.3048 0.2032)
						)
						(arc
							(start -0.3048 -0.2032)
							(mid -0.275042 -0.275042)
							(end -0.2032 -0.3048)
						)
						(arc
							(start 0.2032 -0.3048)
							(mid 0.275042 -0.275042)
							(end 0.3048 -0.2032)
						)
					)
					(width 0)
					(fill yes)
				)
			)
		)
	)
	(footprint ""
		(layer "B.Cu")
		(at 102.089966 -57.2262)
		(property "Reference" "STP58"
			(at 0 0 0)
			(layer "B.SilkS")
			(hide yes)
			(effects
				(font
					(size 1.27 1.27)
				)
				(justify mirror)
			)
		)
		(property "Value" "TPAD28"
			(at -0.0127 -1.8034 0)
			(unlocked yes)
			(layer "B.Fab")
			(hide yes)
			(effects
				(font
					(size 1.016 1.016)
					(thickness 0.1524)
				)
				(justify mirror)
			)
		)
		(property "Device Type" "TPAD28"
			(at -0.0127 -3.3274 0)
			(unlocked yes)
			(layer "B.Fab")
			(hide yes)
			(effects
				(font
					(size 1.016 1.016)
					(thickness 0.1524)
				)
				(justify mirror)
			)
		)
		(duplicate_pad_numbers_are_jumpers no)
		(fp_poly
			(pts
				(arc
					(start 0.3556 0)
					(mid -0.3556 0)
					(end 0.3556 0)
				)
			)
			(stroke
				(width 0)
				(type default)
			)
			(fill no)
			(layer "B.CrtYd")
		)
		(fp_poly
			(pts
				(arc
					(start 0.6096 0)
					(mid -0.6096 0)
					(end 0.6096 0)
				)
			)
			(stroke
				(width 0)
				(type default)
			)
			(fill no)
			(layer "B.Fab")
		)
		(pad "1" smd circle
			(at 0 0 180)
			(size 0.7112 0.7112)
			(layers "B.Cu" "B.Mask" "B.Paste")
			(net "JTAG_IOC_TCK")
		)
	)
	(footprint ""
		(layer "B.Cu")
		(at 91.821 -3.429)
		(property "Reference" "SC1050"
			(at 0 0 0)
			(layer "B.SilkS")
			(hide yes)
			(effects
				(font
					(size 1.27 1.27)
				)
				(justify mirror)
			)
		)
		(property "Value" "SCD1U16V2KX-3GP"
			(at -1.1811 -2.7051 0)
			(unlocked yes)
			(layer "B.Fab")
			(hide yes)
			(effects
				(font
					(size 1.016 1.016)
					(thickness 0.1524)
				)
				(justify mirror)
			)
		)
		(property "Device Type" "C402H22"
			(at -1.1811 -4.2291 0)
			(unlocked yes)
			(layer "B.Fab")
			(hide yes)
			(effects
				(font
					(size 1.016 1.016)
					(thickness 0.1524)
				)
				(justify mirror)
			)
		)
		(duplicate_pad_numbers_are_jumpers no)
		(fp_rect
			(start 0.4318 0.9525)
			(end -0.4318 -0.9525)
			(stroke
				(width 0)
				(type default)
			)
			(fill no)
			(layer "B.CrtYd")
		)
		(fp_rect
			(start 0.4318 0.9525)
			(end -0.4318 -0.9525)
			(stroke
				(width 0)
				(type default)
			)
			(fill no)
			(layer "B.Fab")
		)
		(pad "1" smd custom
			(at 0 -0.4445 180)
			(size 0.1524 0.1524)
			(layers "B.Cu" "B.Mask" "B.Paste")
			(net "P0V955_C")
			(options
				(clearance outline)
				(anchor circle)
			)
			(primitives
				(gr_poly
					(pts
						(arc
							(start 0.3048 0.2032)
							(mid 0.275042 0.275042)
							(end 0.2032 0.3048)
						)
						(arc
							(start -0.2032 0.3048)
							(mid -0.275042 0.275042)
							(end -0.3048 0.2032)
						)
						(arc
							(start -0.3048 -0.2032)
							(mid -0.275042 -0.275042)
							(end -0.2032 -0.3048)
						)
						(arc
							(start 0.2032 -0.3048)
							(mid 0.275042 -0.275042)
							(end 0.3048 -0.2032)
						)
					)
					(width 0)
					(fill yes)
				)
			)
		)
		(pad "2" smd custom
			(at 0 0.4445 180)
			(size 0.1524 0.1524)
			(layers "B.Cu" "B.Mask" "B.Paste")
			(net "GND")
			(options
				(clearance outline)
				(anchor circle)
			)
			(primitives
				(gr_poly
					(pts
						(arc
							(start 0.3048 0.2032)
							(mid 0.275042 0.275042)
							(end 0.2032 0.3048)
						)
						(arc
							(start -0.2032 0.3048)
							(mid -0.275042 0.275042)
							(end -0.3048 0.2032)
						)
						(arc
							(start -0.3048 -0.2032)
							(mid -0.275042 -0.275042)
							(end -0.2032 -0.3048)
						)
						(arc
							(start 0.2032 -0.3048)
							(mid 0.275042 -0.275042)
							(end 0.3048 -0.2032)
						)
					)
					(width 0)
					(fill yes)
				)
			)
		)
	)
	(footprint ""
		(layer "B.Cu")
		(at 121.544842 -82.698082 90)
		(property "Reference" "SC1152"
			(at 0 0 90)
			(layer "B.SilkS")
			(hide yes)
			(effects
				(font
					(size 1.27 1.27)
				)
				(justify mirror)
			)
		)
		(property "Value" "SC1U6D3V1MX-GP"
			(at -1.9177 2.0193 90)
			(unlocked yes)
			(layer "B.Fab")
			(hide yes)
			(effects
				(font
					(size 1.016 1.016)
					(thickness 0.1524)
				)
				(justify mirror)
			)
		)
		(property "Device Type" "C0201H14"
			(at -1.9177 0.4953 90)
			(unlocked yes)
			(layer "B.Fab")
			(hide yes)
			(effects
				(font
					(size 1.016 1.016)
					(thickness 0.1524)
				)
				(justify mirror)
			)
		)
		(duplicate_pad_numbers_are_jumpers no)
		(fp_rect
			(start 0.1524 0.3048)
			(end -0.1524 -0.3048)
			(stroke
				(width 0)
				(type default)
			)
			(fill no)
			(layer "B.CrtYd")
		)
		(fp_poly
			(pts
				(xy 0.2794 0.6477) (xy 0.2794 -0.6477) (xy -0.2794 -0.6477) (xy -0.2794 -0.1905) (xy -0.1524 -0.1905)
				(xy -0.1524 -0.3048) (xy 0.1524 -0.3048) (xy 0.1524 0.3048) (xy -0.1524 0.3048) (xy -0.1524 -0.1778)
				(xy -0.2794 -0.1778) (xy -0.2794 0.6477)
			)
			(stroke
				(width 0)
				(type default)
			)
			(fill no)
			(layer "B.CrtYd")
		)
		(fp_rect
			(start 0.2794 0.6477)
			(end -0.2794 -0.6477)
			(stroke
				(width 0)
				(type default)
			)
			(fill no)
			(layer "B.Fab")
		)
		(pad "1" smd custom
			(at 0 -0.2794 270)
			(size 0.0762 0.0762)
			(layers "B.Cu" "B.Mask" "B.Paste")
			(net "XTAL_VDDA18")
			(options
				(clearance outline)
				(anchor circle)
			)
			(primitives
				(gr_poly
					(pts
						(arc
							(start 0.1524 0.127)
							(mid 0.137521 0.162921)
							(end 0.1016 0.1778)
						)
						(arc
							(start -0.1016 0.1778)
							(mid -0.137521 0.162921)
							(end -0.1524 0.127)
						)
						(arc
							(start -0.1524 -0.127)
							(mid -0.137521 -0.162921)
							(end -0.1016 -0.1778)
						)
						(arc
							(start 0.1016 -0.1778)
							(mid 0.137521 -0.162921)
							(end 0.1524 -0.127)
						)
					)
					(width 0)
					(fill yes)
				)
			)
		)
		(pad "2" smd custom
			(at 0 0.2794 270)
			(size 0.0762 0.0762)
			(layers "B.Cu" "B.Mask" "B.Paste")
			(net "GND")
			(options
				(clearance outline)
				(anchor circle)
			)
			(primitives
				(gr_poly
					(pts
						(arc
							(start 0.1524 0.127)
							(mid 0.137521 0.162921)
							(end 0.1016 0.1778)
						)
						(arc
							(start -0.1016 0.1778)
							(mid -0.137521 0.162921)
							(end -0.1524 0.127)
						)
						(arc
							(start -0.1524 -0.127)
							(mid -0.137521 -0.162921)
							(end -0.1016 -0.1778)
						)
						(arc
							(start 0.1016 -0.1778)
							(mid 0.137521 -0.162921)
							(end 0.1524 -0.127)
						)
					)
					(width 0)
					(fill yes)
				)
			)
		)
	)
	(footprint ""
		(layer "B.Cu")
		(at 80.518 -21.209 180)
		(property "Reference" "PR185"
			(at 0 0 0)
			(layer "B.SilkS")
			(hide yes)
			(effects
				(font
					(size 1.27 1.27)
				)
				(justify mirror)
			)
		)
		(property "Value" "69K8R2F-GP"
			(at -0.064008 -3.993896 180)
			(unlocked yes)
			(layer "B.Fab")
			(hide yes)
			(effects
				(font
					(size 1.016 1.016)
					(thickness 0.1524)
				)
				(justify mirror)
			)
		)
		(property "Device Type" "R402H16"
			(at -0.064008 -5.517896 180)
			(unlocked yes)
			(layer "B.Fab")
			(hide yes)
			(effects
				(font
					(size 1.016 1.016)
					(thickness 0.1524)
				)
				(justify mirror)
			)
		)
		(duplicate_pad_numbers_are_jumpers no)
		(fp_line
			(start 0.508 -0.9398)
			(end 0.508 0.9398)
			(stroke
				(width 0.1524)
				(type default)
			)
			(layer "B.SilkS")
		)
		(fp_line
			(start -0.508 -0.9398)
			(end 0.508 -0.9398)
			(stroke
				(width 0.1524)
				(type default)
			)
			(layer "B.SilkS")
		)
		(fp_rect
			(start 0.508 0.9398)
			(end -0.508 -0.9398)
			(stroke
				(width 0)
				(type default)
			)
			(fill no)
			(layer "B.CrtYd")
		)
		(fp_rect
			(start 0.508 0.9398)
			(end -0.508 -0.9398)
			(stroke
				(width 0)
				(type default)
			)
			(fill no)
			(layer "B.Fab")
		)
		(pad "1" smd custom
			(at 0 -0.4445)
			(size 0.1397 0.1397)
			(layers "B.Cu" "B.Mask" "B.Paste")
			(net "AGND_P0V9_C")
			(options
				(clearance outline)
				(anchor circle)
			)
			(primitives
				(gr_poly
					(pts
						(arc
							(start -0.1778 0.2794)
							(mid -0.249642 0.249642)
							(end -0.2794 0.1778)
						)
						(arc
							(start -0.2794 -0.1778)
							(mid -0.249642 -0.249642)
							(end -0.1778 -0.2794)
						)
						(arc
							(start 0.1778 -0.2794)
							(mid 0.249642 -0.249642)
							(end 0.2794 -0.1778)
						)
						(arc
							(start 0.2794 0.1778)
							(mid 0.249642 0.249642)
							(end 0.1778 0.2794)
						)
					)
					(width 0)
					(fill yes)
				)
			)
		)
		(pad "2" smd custom
			(at 0 0.4445)
			(size 0.1397 0.1397)
			(layers "B.Cu" "B.Mask" "B.Paste")
			(net "VT235_IRIP")
			(options
				(clearance outline)
				(anchor circle)
			)
			(primitives
				(gr_poly
					(pts
						(arc
							(start -0.1778 0.2794)
							(mid -0.249642 0.249642)
							(end -0.2794 0.1778)
						)
						(arc
							(start -0.2794 -0.1778)
							(mid -0.249642 -0.249642)
							(end -0.1778 -0.2794)
						)
						(arc
							(start 0.1778 -0.2794)
							(mid 0.249642 -0.249642)
							(end 0.2794 -0.1778)
						)
						(arc
							(start 0.2794 0.1778)
							(mid 0.249642 0.249642)
							(end 0.1778 0.2794)
						)
					)
					(width 0)
					(fill yes)
				)
			)
		)
	)
	(footprint ""
		(layer "B.Cu")
		(at 133.585966 -31.623 90)
		(property "Reference" "SR655"
			(at 0 0 90)
			(layer "B.SilkS")
			(hide yes)
			(effects
				(font
					(size 1.27 1.27)
				)
				(justify mirror)
			)
		)
		(property "Value" "4K7R2F-GP"
			(at -0.064008 -3.993896 90)
			(unlocked yes)
			(layer "B.Fab")
			(hide yes)
			(effects
				(font
					(size 1.016 1.016)
					(thickness 0.1524)
				)
				(justify mirror)
			)
		)
		(property "Device Type" "R402H16"
			(at -0.064008 -5.517896 90)
			(unlocked yes)
			(layer "B.Fab")
			(hide yes)
			(effects
				(font
					(size 1.016 1.016)
					(thickness 0.1524)
				)
				(justify mirror)
			)
		)
		(duplicate_pad_numbers_are_jumpers no)
		(fp_line
			(start 0.508 -0.9398)
			(end 0.508 0.9398)
			(stroke
				(width 0.1524)
				(type default)
			)
			(layer "B.SilkS")
		)
		(fp_line
			(start -0.508 -0.9398)
			(end 0.508 -0.9398)
			(stroke
				(width 0.1524)
				(type default)
			)
			(layer "B.SilkS")
		)
		(fp_rect
			(start 0.508 0.9398)
			(end -0.508 -0.9398)
			(stroke
				(width 0)
				(type default)
			)
			(fill no)
			(layer "B.CrtYd")
		)
		(fp_rect
			(start 0.508 0.9398)
			(end -0.508 -0.9398)
			(stroke
				(width 0)
				(type default)
			)
			(fill no)
			(layer "B.Fab")
		)
		(pad "1" smd custom
			(at 0 -0.4445 270)
			(size 0.1397 0.1397)
			(layers "B.Cu" "B.Mask" "B.Paste")
			(net "P3V3_STBY")
			(options
				(clearance outline)
				(anchor circle)
			)
			(primitives
				(gr_poly
					(pts
						(arc
							(start -0.1778 0.2794)
							(mid -0.249642 0.249642)
							(end -0.2794 0.1778)
						)
						(arc
							(start -0.2794 -0.1778)
							(mid -0.249642 -0.249642)
							(end -0.1778 -0.2794)
						)
						(arc
							(start 0.1778 -0.2794)
							(mid 0.249642 -0.249642)
							(end 0.2794 -0.1778)
						)
						(arc
							(start 0.2794 0.1778)
							(mid 0.249642 0.249642)
							(end 0.1778 0.2794)
						)
					)
					(width 0)
					(fill yes)
				)
			)
		)
		(pad "2" smd custom
			(at 0 0.4445 270)
			(size 0.1397 0.1397)
			(layers "B.Cu" "B.Mask" "B.Paste")
			(net "P3V3_STBY_R")
			(options
				(clearance outline)
				(anchor circle)
			)
			(primitives
				(gr_poly
					(pts
						(arc
							(start -0.1778 0.2794)
							(mid -0.249642 0.249642)
							(end -0.2794 0.1778)
						)
						(arc
							(start -0.2794 -0.1778)
							(mid -0.249642 -0.249642)
							(end -0.1778 -0.2794)
						)
						(arc
							(start 0.1778 -0.2794)
							(mid 0.249642 -0.249642)
							(end 0.2794 -0.1778)
						)
						(arc
							(start 0.2794 0.1778)
							(mid 0.249642 0.249642)
							(end 0.1778 0.2794)
						)
					)
					(width 0)
					(fill yes)
				)
			)
		)
	)
)
